(kicad_pcb
	(version 20260206)
	(generator "pcbnew")
	(generator_version "10.0")
	(general
		(thickness 1.6)
		(legacy_teardrops no)
	)
	(paper "A4")
	(title_block
		(title "12092022_DA0F0TMDCD0_F0T_Management_Board_D_brd_V3_OCP.brd")
		(comment 1 "Grand Teton / footprints 80-85 of 1440")
	)
	(layers
		(0 "F.Cu" signal "TOP")
		(4 "In1.Cu" signal "GND")
		(6 "In2.Cu" signal "IN1")
		(8 "In3.Cu" signal "GND1")
		(10 "In4.Cu" signal "IN2")
		(12 "In5.Cu" signal "VCC")
		(14 "In6.Cu" signal "VCC1")
		(16 "In7.Cu" signal "IN3")
		(18 "In8.Cu" signal "GND2")
		(20 "In9.Cu" signal "IN4")
		(22 "In10.Cu" signal "GND3")
		(2 "B.Cu" signal "BOTTOM")
		(9 "F.Adhes" user "F.Adhesive")
		(11 "B.Adhes" user "B.Adhesive")
		(13 "F.Paste" user "Package Geometry/Pastemask Top")
		(15 "B.Paste" user "Package Geometry/Pastemask Bottom")
		(5 "F.SilkS" user "Ref Des/Silkscreen Top")
		(7 "B.SilkS" user "Ref Des/Silkscreen Bottom")
		(1 "F.Mask" user "Board Geometry/Soldermask Top")
		(3 "B.Mask" user "Board Geometry/Soldermask Bottom")
		(17 "Dwgs.User" user "User.Drawings")
		(19 "Cmts.User" user "User.Comments")
		(21 "Eco1.User" user "User.Eco1")
		(23 "Eco2.User" user "User.Eco2")
		(25 "Edge.Cuts" user "Board Geometry/Outline")
		(27 "Margin" user)
		(31 "F.CrtYd" user "Package Geometry/Place Bound Top")
		(29 "B.CrtYd" user "Package Geometry/Place Bound Bottom")
		(35 "F.Fab" user "Ref Des/Assembly Top")
		(33 "B.Fab" user "Ref Des/Assembly Bottom")
	)
	(footprint ""
		(layer "F.Cu")
		(at 10.897616 -65.948052)
		(property "Reference" "PC273"
			(at 0 0 0)
			(layer "F.SilkS")
			(hide yes)
			(effects
				(font
					(size 1.27 1.27)
				)
			)
		)
		(property "Value" ""
			(at 0 0 0)
			(layer "F.Fab")
			(effects
				(font
					(size 1.27 1.27)
				)
			)
		)
		(duplicate_pad_numbers_are_jumpers no)
		(fp_line
			(start -0.7874 -0.4064)
			(end 0.7874 -0.4064)
			(stroke
				(width 0.1524)
				(type default)
			)
			(layer "F.SilkS")
		)
		(fp_line
			(start -0.7874 0.4064)
			(end -0.7874 -0.4064)
			(stroke
				(width 0.1524)
				(type default)
			)
			(layer "F.SilkS")
		)
		(fp_line
			(start 0.7874 -0.4064)
			(end 0.7874 0.4064)
			(stroke
				(width 0.1524)
				(type default)
			)
			(layer "F.SilkS")
		)
		(fp_line
			(start 0.7874 0.4064)
			(end -0.7874 0.4064)
			(stroke
				(width 0.1524)
				(type default)
			)
			(layer "F.SilkS")
		)
		(fp_line
			(start -0.67945 -0.305054)
			(end -0.12065 -0.305054)
			(stroke
				(width 0.1)
				(type default)
			)
			(layer "F.Fab")
		)
		(fp_line
			(start -0.67945 0.3048)
			(end -0.67945 -0.305054)
			(stroke
				(width 0.1)
				(type default)
			)
			(layer "F.Fab")
		)
		(fp_line
			(start -0.12065 -0.305054)
			(end -0.12065 -0.2794)
			(stroke
				(width 0.1)
				(type default)
			)
			(layer "F.Fab")
		)
		(fp_line
			(start -0.12065 -0.2794)
			(end 0.12065 -0.2794)
			(stroke
				(width 0.1)
				(type default)
			)
			(layer "F.Fab")
		)
		(fp_line
			(start -0.12065 0.2794)
			(end -0.12065 0.3048)
			(stroke
				(width 0.1)
				(type default)
			)
			(layer "F.Fab")
		)
		(fp_line
			(start -0.12065 0.3048)
			(end -0.67945 0.3048)
			(stroke
				(width 0.1)
				(type default)
			)
			(layer "F.Fab")
		)
		(fp_line
			(start 0.120396 0.2794)
			(end -0.12065 0.2794)
			(stroke
				(width 0.1)
				(type default)
			)
			(layer "F.Fab")
		)
		(fp_line
			(start 0.120396 0.3048)
			(end 0.120396 0.2794)
			(stroke
				(width 0.1)
				(type default)
			)
			(layer "F.Fab")
		)
		(fp_line
			(start 0.12065 -0.3048)
			(end 0.67945 -0.3048)
			(stroke
				(width 0.1)
				(type default)
			)
			(layer "F.Fab")
		)
		(fp_line
			(start 0.12065 -0.2794)
			(end 0.12065 -0.3048)
			(stroke
				(width 0.1)
				(type default)
			)
			(layer "F.Fab")
		)
		(fp_line
			(start 0.67945 -0.3048)
			(end 0.67945 0.3048)
			(stroke
				(width 0.1)
				(type default)
			)
			(layer "F.Fab")
		)
		(fp_line
			(start 0.67945 0.3048)
			(end 0.120396 0.3048)
			(stroke
				(width 0.1)
				(type default)
			)
			(layer "F.Fab")
		)
		(pad "1" smd circle
			(at -0.40005 0)
			(size 0 0)
			(layers "F.Cu" "F.Mask" "F.Paste")
			(net "P3V3_AUX_REF")
		)
		(pad "2" smd circle
			(at 0.40005 0)
			(size 0 0)
			(layers "F.Cu" "F.Mask" "F.Paste")
			(net "GND")
		)
	)
	(footprint ""
		(layer "F.Cu")
		(at 4.572 -58.8264 90)
		(property "Reference" "C241"
			(at 0 0 90)
			(layer "F.SilkS")
			(hide yes)
			(effects
				(font
					(size 1.27 1.27)
				)
			)
		)
		(property "Value" ""
			(at 0 0 90)
			(layer "F.Fab")
			(effects
				(font
					(size 1.27 1.27)
				)
			)
		)
		(duplicate_pad_numbers_are_jumpers no)
		(fp_line
			(start 0.7874 -0.4064)
			(end 0.7874 0.4064)
			(stroke
				(width 0.1524)
				(type default)
			)
			(layer "F.SilkS")
		)
		(fp_line
			(start -0.7874 -0.4064)
			(end 0.7874 -0.4064)
			(stroke
				(width 0.1524)
				(type default)
			)
			(layer "F.SilkS")
		)
		(fp_line
			(start 0.7874 0.4064)
			(end -0.7874 0.4064)
			(stroke
				(width 0.1524)
				(type default)
			)
			(layer "F.SilkS")
		)
		(fp_line
			(start -0.7874 0.4064)
			(end -0.7874 -0.4064)
			(stroke
				(width 0.1524)
				(type default)
			)
			(layer "F.SilkS")
		)
		(fp_line
			(start -0.12065 -0.305054)
			(end -0.12065 -0.2794)
			(stroke
				(width 0.1)
				(type default)
			)
			(layer "F.Fab")
		)
		(fp_line
			(start -0.67945 -0.305054)
			(end -0.12065 -0.305054)
			(stroke
				(width 0.1)
				(type default)
			)
			(layer "F.Fab")
		)
		(fp_line
			(start 0.67945 -0.3048)
			(end 0.67945 0.3048)
			(stroke
				(width 0.1)
				(type default)
			)
			(layer "F.Fab")
		)
		(fp_line
			(start 0.12065 -0.3048)
			(end 0.67945 -0.3048)
			(stroke
				(width 0.1)
				(type default)
			)
			(layer "F.Fab")
		)
		(fp_line
			(start 0.12065 -0.2794)
			(end 0.12065 -0.3048)
			(stroke
				(width 0.1)
				(type default)
			)
			(layer "F.Fab")
		)
		(fp_line
			(start -0.12065 -0.2794)
			(end 0.12065 -0.2794)
			(stroke
				(width 0.1)
				(type default)
			)
			(layer "F.Fab")
		)
		(fp_line
			(start 0.120396 0.2794)
			(end -0.12065 0.2794)
			(stroke
				(width 0.1)
				(type default)
			)
			(layer "F.Fab")
		)
		(fp_line
			(start -0.12065 0.2794)
			(end -0.12065 0.3048)
			(stroke
				(width 0.1)
				(type default)
			)
			(layer "F.Fab")
		)
		(fp_line
			(start 0.67945 0.3048)
			(end 0.120396 0.3048)
			(stroke
				(width 0.1)
				(type default)
			)
			(layer "F.Fab")
		)
		(fp_line
			(start 0.120396 0.3048)
			(end 0.120396 0.2794)
			(stroke
				(width 0.1)
				(type default)
			)
			(layer "F.Fab")
		)
		(fp_line
			(start -0.12065 0.3048)
			(end -0.67945 0.3048)
			(stroke
				(width 0.1)
				(type default)
			)
			(layer "F.Fab")
		)
		(fp_line
			(start -0.67945 0.3048)
			(end -0.67945 -0.305054)
			(stroke
				(width 0.1)
				(type default)
			)
			(layer "F.Fab")
		)
		(pad "1" smd circle
			(at -0.40005 0 90)
			(size 0 0)
			(layers "F.Cu" "F.Mask" "F.Paste")
			(net "P12V_AUX")
		)
		(pad "2" smd circle
			(at 0.40005 0 90)
			(size 0 0)
			(layers "F.Cu" "F.Mask" "F.Paste")
			(net "GND")
		)
	)
	(footprint ""
		(layer "F.Cu")
		(at 26.3398 -105.4608 180)
		(property "Reference" "D17"
			(at 2.3368 1.44653 0)
			(unlocked yes)
			(layer "F.SilkS")
			(effects
				(font
					(size 0.7874 0.5842)
					(thickness 0.1524)
				)
				(justify left)
			)
		)
		(property "Value" ""
			(at 0 0 180)
			(layer "F.Fab")
			(effects
				(font
					(size 1.27 1.27)
				)
			)
		)
		(duplicate_pad_numbers_are_jumpers no)
		(fp_line
			(start 2.343404 0.6985)
			(end 2.216404 0.6985)
			(stroke
				(width 0.1524)
				(type default)
			)
			(layer "F.SilkS")
		)
		(fp_line
			(start 2.343404 -0.6985)
			(end 2.343404 0.6985)
			(stroke
				(width 0.1524)
				(type default)
			)
			(layer "F.SilkS")
		)
		(fp_line
			(start 2.229104 0.6985)
			(end 2.051304 0.6985)
			(stroke
				(width 0.1524)
				(type default)
			)
			(layer "F.SilkS")
		)
		(fp_line
			(start 2.229104 -0.6985)
			(end 2.229104 0.6985)
			(stroke
				(width 0.1524)
				(type default)
			)
			(layer "F.SilkS")
		)
		(fp_line
			(start 2.152904 0.635)
			(end 2.152904 -0.6985)
			(stroke
				(width 0.1524)
				(type default)
			)
			(layer "F.SilkS")
		)
		(fp_line
			(start 2.152904 -0.6985)
			(end 2.343404 -0.6985)
			(stroke
				(width 0.1524)
				(type default)
			)
			(layer "F.SilkS")
		)
		(fp_line
			(start 2.064004 -0.6731)
			(end 2.064004 -0.6985)
			(stroke
				(width 0.1524)
				(type default)
			)
			(layer "F.SilkS")
		)
		(fp_line
			(start 2.064004 -0.6985)
			(end 2.229104 -0.6985)
			(stroke
				(width 0.1524)
				(type default)
			)
			(layer "F.SilkS")
		)
		(fp_line
			(start 2.051304 0.6985)
			(end 2.051304 0.635)
			(stroke
				(width 0.1524)
				(type default)
			)
			(layer "F.SilkS")
		)
		(fp_line
			(start 2.051304 0.635)
			(end 2.152904 0.635)
			(stroke
				(width 0.1524)
				(type default)
			)
			(layer "F.SilkS")
		)
		(fp_line
			(start 2.050796 0.700024)
			(end -2.050796 0.700024)
			(stroke
				(width 0.1524)
				(type default)
			)
			(layer "F.SilkS")
		)
		(fp_line
			(start 2.050796 -0.700024)
			(end 2.050796 0.700024)
			(stroke
				(width 0.1524)
				(type default)
			)
			(layer "F.SilkS")
		)
		(fp_line
			(start 0.293878 -0.500126)
			(end 0.293878 0.500126)
			(stroke
				(width 0.1524)
				(type default)
			)
			(layer "F.SilkS")
		)
		(fp_line
			(start 0.193802 0)
			(end -0.30607 -0.500126)
			(stroke
				(width 0.1524)
				(type default)
			)
			(layer "F.SilkS")
		)
		(fp_line
			(start -0.30607 0.500126)
			(end 0.193802 0)
			(stroke
				(width 0.1524)
				(type default)
			)
			(layer "F.SilkS")
		)
		(fp_line
			(start -0.30607 -0.500126)
			(end -0.30607 0.500126)
			(stroke
				(width 0.1524)
				(type default)
			)
			(layer "F.SilkS")
		)
		(fp_line
			(start -2.050796 0.700024)
			(end -2.050796 -0.700024)
			(stroke
				(width 0.1524)
				(type default)
			)
			(layer "F.SilkS")
		)
		(fp_line
			(start -2.050796 -0.700024)
			(end 2.050796 -0.700024)
			(stroke
				(width 0.1524)
				(type default)
			)
			(layer "F.SilkS")
		)
		(fp_line
			(start 0.899922 0.700024)
			(end -0.899922 0.700024)
			(stroke
				(width 0.1)
				(type default)
			)
			(layer "F.Fab")
		)
		(fp_line
			(start 0.899922 -0.700024)
			(end 0.899922 0.700024)
			(stroke
				(width 0.1)
				(type default)
			)
			(layer "F.Fab")
		)
		(fp_line
			(start -0.899922 0.700024)
			(end -0.899922 -0.700024)
			(stroke
				(width 0.1)
				(type default)
			)
			(layer "F.Fab")
		)
		(fp_line
			(start -0.899922 -0.700024)
			(end 0.899922 -0.700024)
			(stroke
				(width 0.1)
				(type default)
			)
			(layer "F.Fab")
		)
		(fp_text user "-"
			(at 2.1082 -0.92075 0)
			(unlocked yes)
			(layer "F.SilkS")
			(effects
				(font
					(size 1.905 1.4224)
					(thickness 0.1524)
				)
				(justify left)
			)
		)
		(fp_text user "+"
			(at -1.94945 -0.5588 270)
			(unlocked yes)
			(layer "F.SilkS")
			(effects
				(font
					(size 1.905 1.4224)
					(thickness 0.1524)
				)
				(justify left)
			)
		)
		(fp_text user "-"
			(at 3.880104 0.23495 0)
			(unlocked yes)
			(layer "F.Fab")
			(effects
				(font
					(size 1.905 1.4224)
					(thickness 0.1524)
				)
				(justify left)
			)
		)
		(fp_text user "+"
			(at -3.123946 0.762 270)
			(unlocked yes)
			(layer "F.Fab")
			(effects
				(font
					(size 1.905 1.4224)
					(thickness 0.1524)
				)
				(justify left)
			)
		)
		(pad "1" smd rect
			(at -1.199896 0 90)
			(size 0.6604 1.3716)
			(layers "F.Cu" "F.Mask" "F.Paste")
			(net "RST_BMC_HW_OUT")
		)
		(pad "2" smd rect
			(at 1.199896 0 270)
			(size 0.6604 1.3716)
			(layers "F.Cu" "F.Mask" "F.Paste")
			(net "RST_BMC_SELF_HW_D")
		)
	)
	(footprint ""
		(layer "F.Cu")
		(at 32.0548 -20.574 -90)
		(property "Reference" "R31"
			(at 0 0 270)
			(layer "F.SilkS")
			(hide yes)
			(effects
				(font
					(size 1.27 1.27)
				)
			)
		)
		(property "Value" ""
			(at 0 0 270)
			(layer "F.Fab")
			(effects
				(font
					(size 1.27 1.27)
				)
			)
		)
		(duplicate_pad_numbers_are_jumpers no)
		(fp_line
			(start -0.7874 0.4064)
			(end -0.7874 -0.4064)
			(stroke
				(width 0.1524)
				(type default)
			)
			(layer "F.SilkS")
		)
		(fp_line
			(start 0.7874 0.4064)
			(end -0.7874 0.4064)
			(stroke
				(width 0.1524)
				(type default)
			)
			(layer "F.SilkS")
		)
		(fp_line
			(start -0.7874 -0.4064)
			(end 0.7874 -0.4064)
			(stroke
				(width 0.1524)
				(type default)
			)
			(layer "F.SilkS")
		)
		(fp_line
			(start 0.7874 -0.4064)
			(end 0.7874 0.4064)
			(stroke
				(width 0.1524)
				(type default)
			)
			(layer "F.SilkS")
		)
		(fp_line
			(start -0.67945 0.3048)
			(end -0.67945 -0.305054)
			(stroke
				(width 0.1)
				(type default)
			)
			(layer "F.Fab")
		)
		(fp_line
			(start -0.12065 0.3048)
			(end -0.67945 0.3048)
			(stroke
				(width 0.1)
				(type default)
			)
			(layer "F.Fab")
		)
		(fp_line
			(start 0.120396 0.3048)
			(end 0.120396 0.2794)
			(stroke
				(width 0.1)
				(type default)
			)
			(layer "F.Fab")
		)
		(fp_line
			(start 0.67945 0.3048)
			(end 0.120396 0.3048)
			(stroke
				(width 0.1)
				(type default)
			)
			(layer "F.Fab")
		)
		(fp_line
			(start -0.12065 0.2794)
			(end -0.12065 0.3048)
			(stroke
				(width 0.1)
				(type default)
			)
			(layer "F.Fab")
		)
		(fp_line
			(start 0.120396 0.2794)
			(end -0.12065 0.2794)
			(stroke
				(width 0.1)
				(type default)
			)
			(layer "F.Fab")
		)
		(fp_line
			(start -0.12065 -0.2794)
			(end 0.12065 -0.2794)
			(stroke
				(width 0.1)
				(type default)
			)
			(layer "F.Fab")
		)
		(fp_line
			(start 0.12065 -0.2794)
			(end 0.12065 -0.3048)
			(stroke
				(width 0.1)
				(type default)
			)
			(layer "F.Fab")
		)
		(fp_line
			(start 0.12065 -0.3048)
			(end 0.67945 -0.3048)
			(stroke
				(width 0.1)
				(type default)
			)
			(layer "F.Fab")
		)
		(fp_line
			(start 0.67945 -0.3048)
			(end 0.67945 0.3048)
			(stroke
				(width 0.1)
				(type default)
			)
			(layer "F.Fab")
		)
		(fp_line
			(start -0.67945 -0.305054)
			(end -0.12065 -0.305054)
			(stroke
				(width 0.1)
				(type default)
			)
			(layer "F.Fab")
		)
		(fp_line
			(start -0.12065 -0.305054)
			(end -0.12065 -0.2794)
			(stroke
				(width 0.1)
				(type default)
			)
			(layer "F.Fab")
		)
		(pad "1" smd circle
			(at -0.40005 0 270)
			(size 0 0)
			(layers "F.Cu" "F.Mask" "F.Paste")
			(net "P3V3_RGM")
		)
		(pad "2" smd circle
			(at 0.40005 0 270)
			(size 0 0)
			(layers "F.Cu" "F.Mask" "F.Paste")
			(net "V_BMC_DDC_SDA")
		)
	)
	(footprint ""
		(layer "F.Cu")
		(at 27.813 -27.305 180)
		(property "Reference" "C213"
			(at 0 0 180)
			(layer "F.SilkS")
			(hide yes)
			(effects
				(font
					(size 1.27 1.27)
				)
			)
		)
		(property "Value" ""
			(at 0 0 180)
			(layer "F.Fab")
			(effects
				(font
					(size 1.27 1.27)
				)
			)
		)
		(duplicate_pad_numbers_are_jumpers no)
		(fp_line
			(start 0.7874 0.4064)
			(end -0.7874 0.4064)
			(stroke
				(width 0.1524)
				(type default)
			)
			(layer "F.SilkS")
		)
		(fp_line
			(start 0.7874 -0.4064)
			(end 0.7874 0.4064)
			(stroke
				(width 0.1524)
				(type default)
			)
			(layer "F.SilkS")
		)
		(fp_line
			(start -0.7874 0.4064)
			(end -0.7874 -0.4064)
			(stroke
				(width 0.1524)
				(type default)
			)
			(layer "F.SilkS")
		)
		(fp_line
			(start -0.7874 -0.4064)
			(end 0.7874 -0.4064)
			(stroke
				(width 0.1524)
				(type default)
			)
			(layer "F.SilkS")
		)
		(fp_line
			(start 0.67945 0.3048)
			(end 0.120396 0.3048)
			(stroke
				(width 0.1)
				(type default)
			)
			(layer "F.Fab")
		)
		(fp_line
			(start 0.67945 -0.3048)
			(end 0.67945 0.3048)
			(stroke
				(width 0.1)
				(type default)
			)
			(layer "F.Fab")
		)
		(fp_line
			(start 0.12065 -0.2794)
			(end 0.12065 -0.3048)
			(stroke
				(width 0.1)
				(type default)
			)
			(layer "F.Fab")
		)
		(fp_line
			(start 0.12065 -0.3048)
			(end 0.67945 -0.3048)
			(stroke
				(width 0.1)
				(type default)
			)
			(layer "F.Fab")
		)
		(fp_line
			(start 0.120396 0.3048)
			(end 0.120396 0.2794)
			(stroke
				(width 0.1)
				(type default)
			)
			(layer "F.Fab")
		)
		(fp_line
			(start 0.120396 0.2794)
			(end -0.12065 0.2794)
			(stroke
				(width 0.1)
				(type default)
			)
			(layer "F.Fab")
		)
		(fp_line
			(start -0.12065 0.3048)
			(end -0.67945 0.3048)
			(stroke
				(width 0.1)
				(type default)
			)
			(layer "F.Fab")
		)
		(fp_line
			(start -0.12065 0.2794)
			(end -0.12065 0.3048)
			(stroke
				(width 0.1)
				(type default)
			)
			(layer "F.Fab")
		)
		(fp_line
			(start -0.12065 -0.2794)
			(end 0.12065 -0.2794)
			(stroke
				(width 0.1)
				(type default)
			)
			(layer "F.Fab")
		)
		(fp_line
			(start -0.12065 -0.305054)
			(end -0.12065 -0.2794)
			(stroke
				(width 0.1)
				(type default)
			)
			(layer "F.Fab")
		)
		(fp_line
			(start -0.67945 0.3048)
			(end -0.67945 -0.305054)
			(stroke
				(width 0.1)
				(type default)
			)
			(layer "F.Fab")
		)
		(fp_line
			(start -0.67945 -0.305054)
			(end -0.12065 -0.305054)
			(stroke
				(width 0.1)
				(type default)
			)
			(layer "F.Fab")
		)
		(pad "1" smd circle
			(at -0.40005 0 180)
			(size 0 0)
			(layers "F.Cu" "F.Mask" "F.Paste")
			(net "V_BMC_LS_DDC_SDA_R")
		)
		(pad "2" smd circle
			(at 0.40005 0 180)
			(size 0 0)
			(layers "F.Cu" "F.Mask" "F.Paste")
			(net "GND")
		)
	)
	(footprint ""
		(layer "F.Cu")
		(at 6.9342 -17.3228 90)
		(property "Reference" "H2B2"
			(at -1.47447 -6.4262 0)
			(unlocked yes)
			(layer "F.SilkS")
			(effects
				(font
					(size 0.7874 0.5842)
					(thickness 0.1524)
				)
				(justify left)
			)
		)
		(property "Value" ""
			(at 0 0 90)
			(layer "F.Fab")
			(effects
				(font
					(size 1.27 1.27)
				)
			)
		)
		(duplicate_pad_numbers_are_jumpers no)
		(fp_arc
			(start -1.834134 -1.548384)
			(mid 0.134587 -2.396606)
			(end 1.995932 -1.333246)
			(stroke
				(width 0.1524)
				(type default)
			)
			(layer "F.SilkS")
		)
		(fp_arc
			(start 2.2479 0.841756)
			(mid 1.367667 1.972542)
			(end 0 2.4003)
			(stroke
				(width 0.1524)
				(type default)
			)
			(layer "F.SilkS")
		)
		(fp_arc
			(start 0 2.4003)
			(mid -1.444342 1.917049)
			(end -2.307082 0.661924)
			(stroke
				(width 0.1524)
				(type default)
			)
			(layer "F.SilkS")
		)
		(fp_arc
			(start 1.212596 -6.478778)
			(mid 1.432628 -6.433742)
			(end 1.651 -6.381242)
			(stroke
				(width 0.1524)
				(type default)
			)
			(layer "B.SilkS")
		)
		(fp_arc
			(start 5.66801 3.364484)
			(mid 3.261093 5.728087)
			(end 0 6.5913)
			(stroke
				(width 0.1524)
				(type default)
			)
			(layer "B.SilkS")
		)
		(fp_arc
			(start 0 6.5913)
			(mid -3.324795 5.691563)
			(end -5.74167 3.237484)
			(stroke
				(width 0.1524)
				(type default)
			)
			(layer "B.SilkS")
		)
		(fp_circle
			(center 0 0)
			(end 0 6.5913)
			(stroke
				(width 0.1)
				(type default)
			)
			(fill no)
			(layer "B.Fab")
		)
		(fp_circle
			(center 0 0)
			(end 0 2.4003)
			(stroke
				(width 0.1)
				(type default)
			)
			(fill no)
			(layer "F.Fab")
		)
		(pad "" np_thru_hole circle
			(at 0 0 90)
			(size 3.175 3.175)
			(drill 3.175)
			(layers "*.Cu" "*.Mask")
			(clearance 0.381)
			(thermal_gap 0.381)
		)
		(zone
			(layers "F.Cu" "B.Cu" "In1.Cu" "In2.Cu" "In3.Cu" "In4.Cu" "In5.Cu" "In6.Cu"
				"In7.Cu" "In8.Cu" "In9.Cu" "In10.Cu"
			)
			(hatch none 0.5)
			(connect_pads
				(clearance 0)
			)
			(min_thickness 0.25)
			(keepout
				(tracks not_allowed)
				(vias allowed)
				(pads allowed)
				(copperpour not_allowed)
				(footprints allowed)
			)
			(placement
				(enabled no)
				(sheetname "")
			)
			(fill
				(thermal_gap 0.5)
				(thermal_bridge_width 0.5)
				(island_removal_mode 0)
			)
			(polygon
				(pts
					(arc
						(start 9.0297 -17.3228)
						(mid 4.8387 -17.3228)
						(end 9.0297 -17.3228)
					)
				)
			)
		)
	)
)
